(kicad_pcb
	(version 20260206)
	(generator "pcbnew")
	(generator_version "10.0")
	(general
		(thickness 1.6)
		(legacy_teardrops no)
	)
	(paper "A4")
	(title_block
		(title "03242023_DA0F0TMBIJ0_F0T_Motherboard_J_brd_V01_OCP.brd")
		(comment 1 "Grand Teton / footprints 1287-1289 of 6105")
	)
	(layers
		(0 "F.Cu" signal "TOP")
		(4 "In1.Cu" signal "GND")
		(6 "In2.Cu" signal "IN1")
		(8 "In3.Cu" signal "GND1")
		(10 "In4.Cu" signal "IN2")
		(12 "In5.Cu" signal "GND2")
		(14 "In6.Cu" signal "IN3")
		(16 "In7.Cu" signal "GND3")
		(18 "In8.Cu" signal "VCC")
		(20 "In9.Cu" signal "VCC1")
		(22 "In10.Cu" signal "GND4")
		(24 "In11.Cu" signal "IN4")
		(26 "In12.Cu" signal "GND5")
		(28 "In13.Cu" signal "IN5")
		(30 "In14.Cu" signal "GND6")
		(32 "In15.Cu" signal "IN6")
		(34 "In16.Cu" signal "GND7")
		(2 "B.Cu" signal "BOTTOM")
		(9 "F.Adhes" user "F.Adhesive")
		(11 "B.Adhes" user "B.Adhesive")
		(13 "F.Paste" user "Package Geometry/Pastemask Top")
		(15 "B.Paste" user "Package Geometry/Pastemask Bottom")
		(5 "F.SilkS" user "Ref Des/Silkscreen Top")
		(7 "B.SilkS" user "Ref Des/Silkscreen Bottom")
		(1 "F.Mask" user "Board Geometry/Soldermask Top")
		(3 "B.Mask" user "Board Geometry/Soldermask Bottom")
		(17 "Dwgs.User" user "User.Drawings")
		(19 "Cmts.User" user "User.Comments")
		(21 "Eco1.User" user "User.Eco1")
		(23 "Eco2.User" user "User.Eco2")
		(25 "Edge.Cuts" user "Board Geometry/Outline")
		(27 "Margin" user)
		(31 "F.CrtYd" user "Package Geometry/Place Bound Top")
		(29 "B.CrtYd" user "Package Geometry/Place Bound Bottom")
		(35 "F.Fab" user "Ref Des/Assembly Top")
		(33 "B.Fab" user "Ref Des/Assembly Bottom")
	)
	(footprint ""
		(layer "F.Cu")
		(at 157.135576 -37.790374 -90)
		(property "Reference" "U313"
			(at -3.6957 -3.129534 0)
			(unlocked yes)
			(layer "F.SilkS")
			(effects
				(font
					(size 0.7874 0.5842)
					(thickness 0.1524)
				)
				(justify left)
			)
		)
		(property "Value" ""
			(at 0 0 270)
			(layer "F.Fab")
			(effects
				(font
					(size 1.27 1.27)
				)
			)
		)
		(duplicate_pad_numbers_are_jumpers no)
		(fp_line
			(start -0.508 2.921)
			(end -0.508 3.683)
			(stroke
				(width 0.1524)
				(type default)
			)
			(layer "F.SilkS")
		)
		(fp_line
			(start -2.500122 2.500122)
			(end -2.500122 1.778)
			(stroke
				(width 0.1524)
				(type default)
			)
			(layer "F.SilkS")
		)
		(fp_line
			(start -1.778 2.500122)
			(end -2.500122 2.500122)
			(stroke
				(width 0.1524)
				(type default)
			)
			(layer "F.SilkS")
		)
		(fp_line
			(start 2.500122 2.500122)
			(end 1.778 2.500122)
			(stroke
				(width 0.1524)
				(type default)
			)
			(layer "F.SilkS")
		)
		(fp_line
			(start 2.500122 1.778)
			(end 2.500122 2.500122)
			(stroke
				(width 0.1524)
				(type default)
			)
			(layer "F.SilkS")
		)
		(fp_line
			(start 2.921 1.524)
			(end 3.302 1.524)
			(stroke
				(width 0.1524)
				(type default)
			)
			(layer "F.SilkS")
		)
		(fp_line
			(start -2.921 0.508)
			(end -3.302 0.508)
			(stroke
				(width 0.1524)
				(type default)
			)
			(layer "F.SilkS")
		)
		(fp_line
			(start 2.921 -1.016)
			(end 3.683 -1.016)
			(stroke
				(width 0.1524)
				(type default)
			)
			(layer "F.SilkS")
		)
		(fp_line
			(start -2.500122 -1.778)
			(end -2.500122 -2.500122)
			(stroke
				(width 0.1524)
				(type default)
			)
			(layer "F.SilkS")
		)
		(fp_line
			(start -2.500122 -2.500122)
			(end -1.778 -2.500122)
			(stroke
				(width 0.1524)
				(type default)
			)
			(layer "F.SilkS")
		)
		(fp_line
			(start 1.778 -2.500122)
			(end 2.500122 -2.500122)
			(stroke
				(width 0.1524)
				(type default)
			)
			(layer "F.SilkS")
		)
		(fp_line
			(start 2.500122 -2.500122)
			(end 2.500122 -1.778)
			(stroke
				(width 0.1524)
				(type default)
			)
			(layer "F.SilkS")
		)
		(fp_line
			(start 0 -2.921)
			(end 0 -3.302)
			(stroke
				(width 0.1524)
				(type default)
			)
			(layer "F.SilkS")
		)
		(fp_poly
			(pts
				(xy -2.72288 -2.24282) (xy -3.642106 -2.549144) (xy -3.029458 -3.161792)
			)
			(stroke
				(width 0)
				(type default)
			)
			(fill yes)
			(layer "F.SilkS")
		)
		(fp_line
			(start -0.508 2.921)
			(end -0.508 3.683)
			(stroke
				(width 0.1)
				(type default)
			)
			(layer "F.Fab")
		)
		(fp_line
			(start -2.500122 2.500122)
			(end -2.500122 -2.500122)
			(stroke
				(width 0.1)
				(type default)
			)
			(layer "F.Fab")
		)
		(fp_line
			(start 2.500122 2.500122)
			(end -2.500122 2.500122)
			(stroke
				(width 0.1)
				(type default)
			)
			(layer "F.Fab")
		)
		(fp_line
			(start 2.921 1.524)
			(end 3.302 1.524)
			(stroke
				(width 0.1)
				(type default)
			)
			(layer "F.Fab")
		)
		(fp_line
			(start -2.921 0.508)
			(end -3.302 0.508)
			(stroke
				(width 0.1)
				(type default)
			)
			(layer "F.Fab")
		)
		(fp_line
			(start 2.921 -1.016)
			(end 3.683 -1.016)
			(stroke
				(width 0.1)
				(type default)
			)
			(layer "F.Fab")
		)
		(fp_line
			(start -2.500122 -2.500122)
			(end 2.500122 -2.500122)
			(stroke
				(width 0.1)
				(type default)
			)
			(layer "F.Fab")
		)
		(fp_line
			(start 2.500122 -2.500122)
			(end 2.500122 2.500122)
			(stroke
				(width 0.1)
				(type default)
			)
			(layer "F.Fab")
		)
		(fp_line
			(start 0 -2.921)
			(end 0 -3.302)
			(stroke
				(width 0.1)
				(type default)
			)
			(layer "F.Fab")
		)
		(fp_poly
			(pts
				(xy -3.7592 -1.933194) (xy -2.892806 -1.500124) (xy -3.7592 -1.0668)
			)
			(stroke
				(width 0)
				(type default)
			)
			(fill yes)
			(layer "F.Fab")
		)
		(fp_text user "14"
			(at 1.507236 3.879596 0)
			(unlocked yes)
			(layer "F.SilkS")
			(effects
				(font
					(size 0.635 0.4064)
					(thickness 0.1524)
				)
			)
		)
		(fp_text user "8"
			(at -3.080004 2.513076 0)
			(unlocked yes)
			(layer "F.SilkS")
			(effects
				(font
					(size 0.635 0.4064)
					(thickness 0.1524)
				)
			)
		)
		(fp_text user "15"
			(at 3.253232 2.2352 0)
			(unlocked yes)
			(layer "F.SilkS")
			(effects
				(font
					(size 0.635 0.4064)
					(thickness 0.1524)
				)
			)
		)
		(fp_text user "7"
			(at -3.147568 1.8034 0)
			(unlocked yes)
			(layer "F.SilkS")
			(effects
				(font
					(size 0.635 0.4064)
					(thickness 0.1524)
				)
			)
		)
		(fp_text user "21"
			(at 3.291332 -1.75768 0)
			(unlocked yes)
			(layer "F.SilkS")
			(effects
				(font
					(size 0.635 0.4064)
					(thickness 0.1524)
				)
			)
		)
		(fp_text user "28"
			(at -2.091944 -3.461004 0)
			(unlocked yes)
			(layer "F.SilkS")
			(effects
				(font
					(size 0.635 0.4064)
					(thickness 0.1524)
				)
			)
		)
		(fp_text user "22"
			(at 2.942336 -3.930904 0)
			(unlocked yes)
			(layer "F.SilkS")
			(effects
				(font
					(size 0.635 0.4064)
					(thickness 0.1524)
				)
			)
		)
		(fp_text user "8"
			(at -1.8796 3.253232 270)
			(unlocked yes)
			(layer "F.Fab")
			(effects
				(font
					(size 0.635 0.4064)
					(thickness 0.1524)
				)
			)
		)
		(fp_text user "14"
			(at 2.1336 3.253232 270)
			(unlocked yes)
			(layer "F.Fab")
			(effects
				(font
					(size 0.635 0.4064)
					(thickness 0.1524)
				)
			)
		)
		(fp_text user "15"
			(at 3.253232 2.2352 0)
			(unlocked yes)
			(layer "F.Fab")
			(effects
				(font
					(size 0.635 0.4064)
					(thickness 0.1524)
				)
			)
		)
		(fp_text user "7"
			(at -3.147568 1.8034 0)
			(unlocked yes)
			(layer "F.Fab")
			(effects
				(font
					(size 0.635 0.4064)
					(thickness 0.1524)
				)
			)
		)
		(fp_text user "21"
			(at 3.227832 -2.2606 0)
			(unlocked yes)
			(layer "F.Fab")
			(effects
				(font
					(size 0.635 0.4064)
					(thickness 0.1524)
				)
			)
		)
		(fp_text user "28"
			(at -2.2098 -3.172968 270)
			(unlocked yes)
			(layer "F.Fab")
			(effects
				(font
					(size 0.635 0.4064)
					(thickness 0.1524)
				)
			)
		)
		(fp_text user "22"
			(at 2.2352 -3.172968 270)
			(unlocked yes)
			(layer "F.Fab")
			(effects
				(font
					(size 0.635 0.4064)
					(thickness 0.1524)
				)
			)
		)
		(pad "1" smd rect
			(at -2.412492 -1.500124)
			(size 0.254 0.7366)
			(layers "F.Cu" "F.Mask" "F.Paste")
			(net "USB2_PCH_0_R_DN")
		)
		(pad "2" smd rect
			(at -2.412492 -0.999998)
			(size 0.254 0.7366)
			(layers "F.Cu" "F.Mask" "F.Paste")
			(net "USB2_PCH_0_R_DP")
		)
		(pad "3" smd rect
			(at -2.412492 -0.499872)
			(size 0.254 0.7366)
			(layers "F.Cu" "F.Mask" "F.Paste")
			(net "USB2_HUB_2_EXT_DN")
		)
		(pad "4" smd rect
			(at -2.412492 0)
			(size 0.254 0.7366)
			(layers "F.Cu" "F.Mask" "F.Paste")
			(net "USB2_HUB_2_EXT_DP")
		)
		(pad "5" smd rect
			(at -2.412492 0.499872)
			(size 0.254 0.7366)
			(layers "F.Cu" "F.Mask" "F.Paste")
			(net "P3V3_AUX_USB_HUB_2")
		)
		(pad "6" smd rect
			(at -2.412492 0.999998)
			(size 0.254 0.7366)
			(layers "F.Cu" "F.Mask" "F.Paste")
			(net "NC_USB_HUB_2_DM2")
		)
		(pad "7" smd rect
			(at -2.412492 1.500124)
			(size 0.254 0.7366)
			(layers "F.Cu" "F.Mask" "F.Paste")
			(net "NC_USB_HUB_2_DP2")
		)
		(pad "8" smd rect
			(at -1.500124 2.412492 270)
			(size 0.254 0.7366)
			(layers "F.Cu" "F.Mask" "F.Paste")
			(net "USB_HUB_2_RREF")
		)
		(pad "9" smd rect
			(at -0.999998 2.412492 270)
			(size 0.254 0.7366)
			(layers "F.Cu" "F.Mask" "F.Paste")
			(net "P3V3_AUX_USB_HUB_2")
		)
		(pad "10" smd rect
			(at -0.499872 2.412492 270)
			(size 0.254 0.7366)
			(layers "F.Cu" "F.Mask" "F.Paste")
			(net "USB_HUB_2_XTAL_IN")
		)
		(pad "11" smd rect
			(at 0 2.412492 270)
			(size 0.254 0.7366)
			(layers "F.Cu" "F.Mask" "F.Paste")
			(net "USB_HUB_2_XTAL_OUT")
		)
		(pad "12" smd rect
			(at 0.499872 2.412492 270)
			(size 0.254 0.7366)
			(layers "F.Cu" "F.Mask" "F.Paste")
			(net "NC_USB_HUB_2_DM3")
		)
		(pad "13" smd rect
			(at 0.999998 2.412492 270)
			(size 0.254 0.7366)
			(layers "F.Cu" "F.Mask" "F.Paste")
			(net "NC_USB_HUB_2_DP3")
		)
		(pad "14" smd rect
			(at 1.500124 2.412492 270)
			(size 0.254 0.7366)
			(layers "F.Cu" "F.Mask" "F.Paste")
			(net "P3V3_AUX_USB_HUB_2")
		)
		(pad "15" smd rect
			(at 2.412492 1.500124)
			(size 0.254 0.7366)
			(layers "F.Cu" "F.Mask" "F.Paste")
			(net "NC_USB_HUB_2_DM4")
		)
		(pad "16" smd rect
			(at 2.412492 0.999998)
			(size 0.254 0.7366)
			(layers "F.Cu" "F.Mask" "F.Paste")
			(net "NC_USB_HUB_2_DP4")
		)
		(pad "17" smd rect
			(at 2.412492 0.499872)
			(size 0.254 0.7366)
			(layers "F.Cu" "F.Mask" "F.Paste")
			(net "RST_USB_HUB_2_R_N")
		)
		(pad "18" smd rect
			(at 2.412492 0)
			(size 0.254 0.7366)
			(layers "F.Cu" "F.Mask" "F.Paste")
			(net "USB_HUB_2_TEST")
		)
		(pad "19" smd rect
			(at 2.412492 -0.499872)
			(size 0.254 0.7366)
			(layers "F.Cu" "F.Mask" "F.Paste")
			(net "USB_HUB_2_OVCUR4")
		)
		(pad "20" smd rect
			(at 2.412492 -0.999998)
			(size 0.254 0.7366)
			(layers "F.Cu" "F.Mask" "F.Paste")
			(net "USB_HUB_2_OVCUR3")
		)
		(pad "21" smd rect
			(at 2.412492 -1.500124)
			(size 0.254 0.7366)
			(layers "F.Cu" "F.Mask" "F.Paste")
			(net "USB_HUB_2_DVDD")
		)
		(pad "22" smd rect
			(at 1.500124 -2.412492 270)
			(size 0.254 0.7366)
			(layers "F.Cu" "F.Mask" "F.Paste")
			(net "USB_HUB_2_PSELF")
		)
		(pad "23" smd rect
			(at 0.999998 -2.412492 270)
			(size 0.254 0.7366)
			(layers "F.Cu" "F.Mask" "F.Paste")
			(net "USB_HUB_2_PGANG")
		)
		(pad "24" smd rect
			(at 0.499872 -2.412492 270)
			(size 0.254 0.7366)
			(layers "F.Cu" "F.Mask" "F.Paste")
			(net "USB_HUB_2_OVCUR2")
		)
		(pad "25" smd rect
			(at 0 -2.412492 270)
			(size 0.254 0.7366)
			(layers "F.Cu" "F.Mask" "F.Paste")
			(net "USB_HUB_2_OVCUR1")
		)
		(pad "26" smd rect
			(at -0.499872 -2.412492 270)
			(size 0.254 0.7366)
			(layers "F.Cu" "F.Mask" "F.Paste")
			(net "NC_USB_HUB_2_SDA")
		)
		(pad "27" smd rect
			(at -0.999998 -2.412492 270)
			(size 0.254 0.7366)
			(layers "F.Cu" "F.Mask" "F.Paste")
			(net "P3V3_AUX_USB_HUB_2")
		)
		(pad "28" smd rect
			(at -1.500124 -2.412492 270)
			(size 0.254 0.7366)
			(layers "F.Cu" "F.Mask" "F.Paste")
			(net "P3V3_AUX_USB_HUB_2")
		)
		(pad "TH" smd rect
			(at 0 0 270)
			(size 3.556 3.556)
			(layers "F.Cu" "F.Mask" "F.Paste")
			(net "GND")
		)
		(zone
			(layer "F.Cu")
			(hatch none 0.5)
			(connect_pads
				(clearance 0)
			)
			(min_thickness 0.25)
			(keepout
				(tracks not_allowed)
				(vias allowed)
				(pads allowed)
				(copperpour not_allowed)
				(footprints allowed)
			)
			(placement
				(enabled no)
				(sheetname "")
			)
			(fill
				(thermal_gap 0.5)
				(thermal_bridge_width 0.5)
				(island_removal_mode 0)
			)
			(polygon
				(pts
					(xy 159.116776 -36.850574) (xy 158.964376 -36.850574) (xy 158.964376 -39.619174) (xy 155.306776 -39.619174)
					(xy 155.306776 -35.961574) (xy 158.964376 -35.961574) (xy 158.964376 -36.825174) (xy 159.116776 -36.825174)
					(xy 159.116776 -35.809174) (xy 155.154376 -35.809174) (xy 155.154376 -39.771574) (xy 159.116776 -39.771574)
				)
			)
		)
	)
	(footprint ""
		(layer "F.Cu")
		(at 118.542816 -247.715278 90)
		(property "Reference" "C249"
			(at 0 0 90)
			(layer "F.SilkS")
			(hide yes)
			(effects
				(font
					(size 1.27 1.27)
				)
			)
		)
		(property "Value" ""
			(at 0 0 90)
			(layer "F.Fab")
			(effects
				(font
					(size 1.27 1.27)
				)
			)
		)
		(duplicate_pad_numbers_are_jumpers no)
		(fp_line
			(start 0.7874 -0.4064)
			(end 0.7874 0.4064)
			(stroke
				(width 0.1524)
				(type default)
			)
			(layer "F.SilkS")
		)
		(fp_line
			(start -0.7874 -0.4064)
			(end 0.7874 -0.4064)
			(stroke
				(width 0.1524)
				(type default)
			)
			(layer "F.SilkS")
		)
		(fp_line
			(start 0.7874 0.4064)
			(end -0.7874 0.4064)
			(stroke
				(width 0.1524)
				(type default)
			)
			(layer "F.SilkS")
		)
		(fp_line
			(start -0.7874 0.4064)
			(end -0.7874 -0.4064)
			(stroke
				(width 0.1524)
				(type default)
			)
			(layer "F.SilkS")
		)
		(fp_line
			(start -0.12065 -0.305054)
			(end -0.12065 -0.2794)
			(stroke
				(width 0.1)
				(type default)
			)
			(layer "F.Fab")
		)
		(fp_line
			(start -0.67945 -0.305054)
			(end -0.12065 -0.305054)
			(stroke
				(width 0.1)
				(type default)
			)
			(layer "F.Fab")
		)
		(fp_line
			(start 0.67945 -0.3048)
			(end 0.67945 0.3048)
			(stroke
				(width 0.1)
				(type default)
			)
			(layer "F.Fab")
		)
		(fp_line
			(start 0.12065 -0.3048)
			(end 0.67945 -0.3048)
			(stroke
				(width 0.1)
				(type default)
			)
			(layer "F.Fab")
		)
		(fp_line
			(start 0.12065 -0.2794)
			(end 0.12065 -0.3048)
			(stroke
				(width 0.1)
				(type default)
			)
			(layer "F.Fab")
		)
		(fp_line
			(start -0.12065 -0.2794)
			(end 0.12065 -0.2794)
			(stroke
				(width 0.1)
				(type default)
			)
			(layer "F.Fab")
		)
		(fp_line
			(start 0.120396 0.2794)
			(end -0.12065 0.2794)
			(stroke
				(width 0.1)
				(type default)
			)
			(layer "F.Fab")
		)
		(fp_line
			(start -0.12065 0.2794)
			(end -0.12065 0.3048)
			(stroke
				(width 0.1)
				(type default)
			)
			(layer "F.Fab")
		)
		(fp_line
			(start 0.67945 0.3048)
			(end 0.120396 0.3048)
			(stroke
				(width 0.1)
				(type default)
			)
			(layer "F.Fab")
		)
		(fp_line
			(start 0.120396 0.3048)
			(end 0.120396 0.2794)
			(stroke
				(width 0.1)
				(type default)
			)
			(layer "F.Fab")
		)
		(fp_line
			(start -0.12065 0.3048)
			(end -0.67945 0.3048)
			(stroke
				(width 0.1)
				(type default)
			)
			(layer "F.Fab")
		)
		(fp_line
			(start -0.67945 0.3048)
			(end -0.67945 -0.305054)
			(stroke
				(width 0.1)
				(type default)
			)
			(layer "F.Fab")
		)
		(pad "1" smd circle
			(at -0.40005 0 90)
			(size 0 0)
			(layers "F.Cu" "F.Mask" "F.Paste")
			(net "PVCCIN_CPU1")
		)
		(pad "2" smd circle
			(at 0.40005 0 90)
			(size 0 0)
			(layers "F.Cu" "F.Mask" "F.Paste")
			(net "GND")
		)
	)
	(footprint ""
		(layer "F.Cu")
		(at 8.75919 -101.854 180)
		(property "Reference" "R3653"
			(at 0 0 180)
			(layer "F.SilkS")
			(hide yes)
			(effects
				(font
					(size 1.27 1.27)
				)
			)
		)
		(property "Value" ""
			(at 0 0 180)
			(layer "F.Fab")
			(effects
				(font
					(size 1.27 1.27)
				)
			)
		)
		(duplicate_pad_numbers_are_jumpers no)
		(fp_line
			(start 0.7874 0.4064)
			(end -0.7874 0.4064)
			(stroke
				(width 0.1524)
				(type default)
			)
			(layer "F.SilkS")
		)
		(fp_line
			(start 0.7874 -0.4064)
			(end 0.7874 0.4064)
			(stroke
				(width 0.1524)
				(type default)
			)
			(layer "F.SilkS")
		)
		(fp_line
			(start -0.7874 0.4064)
			(end -0.7874 -0.4064)
			(stroke
				(width 0.1524)
				(type default)
			)
			(layer "F.SilkS")
		)
		(fp_line
			(start -0.7874 -0.4064)
			(end 0.7874 -0.4064)
			(stroke
				(width 0.1524)
				(type default)
			)
			(layer "F.SilkS")
		)
		(fp_line
			(start 0.67945 0.3048)
			(end 0.120396 0.3048)
			(stroke
				(width 0.1)
				(type default)
			)
			(layer "F.Fab")
		)
		(fp_line
			(start 0.67945 -0.3048)
			(end 0.67945 0.3048)
			(stroke
				(width 0.1)
				(type default)
			)
			(layer "F.Fab")
		)
		(fp_line
			(start 0.12065 -0.2794)
			(end 0.12065 -0.3048)
			(stroke
				(width 0.1)
				(type default)
			)
			(layer "F.Fab")
		)
		(fp_line
			(start 0.12065 -0.3048)
			(end 0.67945 -0.3048)
			(stroke
				(width 0.1)
				(type default)
			)
			(layer "F.Fab")
		)
		(fp_line
			(start 0.120396 0.3048)
			(end 0.120396 0.2794)
			(stroke
				(width 0.1)
				(type default)
			)
			(layer "F.Fab")
		)
		(fp_line
			(start 0.120396 0.2794)
			(end -0.12065 0.2794)
			(stroke
				(width 0.1)
				(type default)
			)
			(layer "F.Fab")
		)
		(fp_line
			(start -0.12065 0.3048)
			(end -0.67945 0.3048)
			(stroke
				(width 0.1)
				(type default)
			)
			(layer "F.Fab")
		)
		(fp_line
			(start -0.12065 0.2794)
			(end -0.12065 0.3048)
			(stroke
				(width 0.1)
				(type default)
			)
			(layer "F.Fab")
		)
		(fp_line
			(start -0.12065 -0.2794)
			(end 0.12065 -0.2794)
			(stroke
				(width 0.1)
				(type default)
			)
			(layer "F.Fab")
		)
		(fp_line
			(start -0.12065 -0.305054)
			(end -0.12065 -0.2794)
			(stroke
				(width 0.1)
				(type default)
			)
			(layer "F.Fab")
		)
		(fp_line
			(start -0.67945 0.3048)
			(end -0.67945 -0.305054)
			(stroke
				(width 0.1)
				(type default)
			)
			(layer "F.Fab")
		)
		(fp_line
			(start -0.67945 -0.305054)
			(end -0.12065 -0.305054)
			(stroke
				(width 0.1)
				(type default)
			)
			(layer "F.Fab")
		)
		(pad "1" smd circle
			(at -0.40005 0 180)
			(size 0 0)
			(layers "F.Cu" "F.Mask" "F.Paste")
			(net "USB_HUB_RREF")
		)
		(pad "2" smd circle
			(at 0.40005 0 180)
			(size 0 0)
			(layers "F.Cu" "F.Mask" "F.Paste")
			(net "GND")
		)
	)
)
